# S9S_MB_2U (Grand Teton) — schematic netlist excerpt (pin names and nets, part order shuffled) for the footprints in the layout excerpt that follows; sources: Cadence DE-HDL packaged netlist, KiCad conversion of 03242023_DA0F0TMBIJ0_F0T_Motherboard_J_brd_V01_OCP.brd

R3583  Q_RES  2.2K 5% CHIP  pkg 0402LF  page 231 : A = P3V3_AUX ; B = SMB_IOEXP_3V3AUX_SDA
R3429  Q_RES  100K 1% EMPTY  pkg 0402LF  page 147 : A = P3V3_AUX ; B = GPU_BASE_HMC_READY

(kicad_pcb
	(version 20260206)
	(generator "pcbnew")
	(generator_version "10.0")
	(general
		(thickness 1.6)
		(legacy_teardrops no)
	)
	(paper "A4")
	(title_block
		(title "03242023_DA0F0TMBIJ0_F0T_Motherboard_J_brd_V01_OCP.brd")
		(comment 1 "Grand Teton / footprints 1188-1189 of 6105")
	)
	(layers
		(0 "F.Cu" signal "TOP")
		(4 "In1.Cu" signal "GND")
		(6 "In2.Cu" signal "IN1")
		(8 "In3.Cu" signal "GND1")
		(10 "In4.Cu" signal "IN2")
		(12 "In5.Cu" signal "GND2")
		(14 "In6.Cu" signal "IN3")
		(16 "In7.Cu" signal "GND3")
		(18 "In8.Cu" signal "VCC")
		(20 "In9.Cu" signal "VCC1")
		(22 "In10.Cu" signal "GND4")
		(24 "In11.Cu" signal "IN4")
		(26 "In12.Cu" signal "GND5")
		(28 "In13.Cu" signal "IN5")
		(30 "In14.Cu" signal "GND6")
		(32 "In15.Cu" signal "IN6")
		(34 "In16.Cu" signal "GND7")
		(2 "B.Cu" signal "BOTTOM")
		(9 "F.Adhes" user "F.Adhesive")
		(11 "B.Adhes" user "B.Adhesive")
		(13 "F.Paste" user "Package Geometry/Pastemask Top")
		(15 "B.Paste" user "Package Geometry/Pastemask Bottom")
		(5 "F.SilkS" user "Ref Des/Silkscreen Top")
		(7 "B.SilkS" user "Ref Des/Silkscreen Bottom")
		(1 "F.Mask" user "Board Geometry/Soldermask Top")
		(3 "B.Mask" user "Board Geometry/Soldermask Bottom")
		(17 "Dwgs.User" user "User.Drawings")
		(19 "Cmts.User" user "User.Comments")
		(21 "Eco1.User" user "User.Eco1")
		(23 "Eco2.User" user "User.Eco2")
		(25 "Edge.Cuts" user "Board Geometry/Outline")
		(27 "Margin" user)
		(31 "F.CrtYd" user "Package Geometry/Place Bound Top")
		(29 "B.CrtYd" user "Package Geometry/Place Bound Bottom")
		(35 "F.Fab" user "Ref Des/Assembly Top")
		(33 "B.Fab" user "Ref Des/Assembly Bottom")
	)
	(footprint ""
		(layer "F.Cu")
		(at 169.441622 -420.511478)
		(property "Reference" "R3429"
			(at 0 0 0)
			(layer "F.SilkS")
			(hide yes)
			(effects
				(font
					(size 1.27 1.27)
				)
			)
		)
		(property "Value" ""
			(at 0 0 0)
			(layer "F.Fab")
			(effects
				(font
					(size 1.27 1.27)
				)
			)
		)
		(duplicate_pad_numbers_are_jumpers no)
		(fp_line
			(start -0.7874 -0.4064)
			(end 0.7874 -0.4064)
			(stroke
				(width 0.1524)
				(type default)
			)
			(layer "F.SilkS")
		)
		(fp_line
			(start -0.7874 0.4064)
			(end -0.7874 -0.4064)
			(stroke
				(width 0.1524)
				(type default)
			)
			(layer "F.SilkS")
		)
		(fp_line
			(start 0.7874 -0.4064)
			(end 0.7874 0.4064)
			(stroke
				(width 0.1524)
				(type default)
			)
			(layer "F.SilkS")
		)
		(fp_line
			(start 0.7874 0.4064)
			(end -0.7874 0.4064)
			(stroke
				(width 0.1524)
				(type default)
			)
			(layer "F.SilkS")
		)
		(fp_line
			(start -0.67945 -0.305054)
			(end -0.12065 -0.305054)
			(stroke
				(width 0.1)
				(type default)
			)
			(layer "F.Fab")
		)
		(fp_line
			(start -0.67945 0.3048)
			(end -0.67945 -0.305054)
			(stroke
				(width 0.1)
				(type default)
			)
			(layer "F.Fab")
		)
		(fp_line
			(start -0.12065 -0.305054)
			(end -0.12065 -0.2794)
			(stroke
				(width 0.1)
				(type default)
			)
			(layer "F.Fab")
		)
		(fp_line
			(start -0.12065 -0.2794)
			(end 0.12065 -0.2794)
			(stroke
				(width 0.1)
				(type default)
			)
			(layer "F.Fab")
		)
		(fp_line
			(start -0.12065 0.2794)
			(end -0.12065 0.3048)
			(stroke
				(width 0.1)
				(type default)
			)
			(layer "F.Fab")
		)
		(fp_line
			(start -0.12065 0.3048)
			(end -0.67945 0.3048)
			(stroke
				(width 0.1)
				(type default)
			)
			(layer "F.Fab")
		)
		(fp_line
			(start 0.120396 0.2794)
			(end -0.12065 0.2794)
			(stroke
				(width 0.1)
				(type default)
			)
			(layer "F.Fab")
		)
		(fp_line
			(start 0.120396 0.3048)
			(end 0.120396 0.2794)
			(stroke
				(width 0.1)
				(type default)
			)
			(layer "F.Fab")
		)
		(fp_line
			(start 0.12065 -0.3048)
			(end 0.67945 -0.3048)
			(stroke
				(width 0.1)
				(type default)
			)
			(layer "F.Fab")
		)
		(fp_line
			(start 0.12065 -0.2794)
			(end 0.12065 -0.3048)
			(stroke
				(width 0.1)
				(type default)
			)
			(layer "F.Fab")
		)
		(fp_line
			(start 0.67945 -0.3048)
			(end 0.67945 0.3048)
			(stroke
				(width 0.1)
				(type default)
			)
			(layer "F.Fab")
		)
		(fp_line
			(start 0.67945 0.3048)
			(end 0.120396 0.3048)
			(stroke
				(width 0.1)
				(type default)
			)
			(layer "F.Fab")
		)
		(pad "1" smd circle
			(at -0.40005 0)
			(size 0 0)
			(layers "F.Cu" "F.Mask" "F.Paste")
			(net "P3V3_AUX")
		)
		(pad "2" smd circle
			(at 0.40005 0)
			(size 0 0)
			(layers "F.Cu" "F.Mask" "F.Paste")
			(net "GPU_BASE_HMC_READY")
		)
	)
	(footprint ""
		(layer "F.Cu")
		(at 111.332772 -133.663182)
		(property "Reference" "R3583"
			(at 0 0 0)
			(layer "F.SilkS")
			(hide yes)
			(effects
				(font
					(size 1.27 1.27)
				)
			)
		)
		(property "Value" ""
			(at 0 0 0)
			(layer "F.Fab")
			(effects
				(font
					(size 1.27 1.27)
				)
			)
		)
		(duplicate_pad_numbers_are_jumpers no)
		(fp_line
			(start -0.7874 -0.4064)
			(end 0.7874 -0.4064)
			(stroke
				(width 0.1524)
				(type default)
			)
			(layer "F.SilkS")
		)
		(fp_line
			(start -0.7874 0.4064)
			(end -0.7874 -0.4064)
			(stroke
				(width 0.1524)
				(type default)
			)
			(layer "F.SilkS")
		)
		(fp_line
			(start 0.7874 -0.4064)
			(end 0.7874 0.4064)
			(stroke
				(width 0.1524)
				(type default)
			)
			(layer "F.SilkS")
		)
		(fp_line
			(start 0.7874 0.4064)
			(end -0.7874 0.4064)
			(stroke
				(width 0.1524)
				(type default)
			)
			(layer "F.SilkS")
		)
		(fp_line
			(start -0.67945 -0.305054)
			(end -0.12065 -0.305054)
			(stroke
				(width 0.1)
				(type default)
			)
			(layer "F.Fab")
		)
		(fp_line
			(start -0.67945 0.3048)
			(end -0.67945 -0.305054)
			(stroke
				(width 0.1)
				(type default)
			)
			(layer "F.Fab")
		)
		(fp_line
			(start -0.12065 -0.305054)
			(end -0.12065 -0.2794)
			(stroke
				(width 0.1)
				(type default)
			)
			(layer "F.Fab")
		)
		(fp_line
			(start -0.12065 -0.2794)
			(end 0.12065 -0.2794)
			(stroke
				(width 0.1)
				(type default)
			)
			(layer "F.Fab")
		)
		(fp_line
			(start -0.12065 0.2794)
			(end -0.12065 0.3048)
			(stroke
				(width 0.1)
				(type default)
			)
			(layer "F.Fab")
		)
		(fp_line
			(start -0.12065 0.3048)
			(end -0.67945 0.3048)
			(stroke
				(width 0.1)
				(type default)
			)
			(layer "F.Fab")
		)
		(fp_line
			(start 0.120396 0.2794)
			(end -0.12065 0.2794)
			(stroke
				(width 0.1)
				(type default)
			)
			(layer "F.Fab")
		)
		(fp_line
			(start 0.120396 0.3048)
			(end 0.120396 0.2794)
			(stroke
				(width 0.1)
				(type default)
			)
			(layer "F.Fab")
		)
		(fp_line
			(start 0.12065 -0.3048)
			(end 0.67945 -0.3048)
			(stroke
				(width 0.1)
				(type default)
			)
			(layer "F.Fab")
		)
		(fp_line
			(start 0.12065 -0.2794)
			(end 0.12065 -0.3048)
			(stroke
				(width 0.1)
				(type default)
			)
			(layer "F.Fab")
		)
		(fp_line
			(start 0.67945 -0.3048)
			(end 0.67945 0.3048)
			(stroke
				(width 0.1)
				(type default)
			)
			(layer "F.Fab")
		)
		(fp_line
			(start 0.67945 0.3048)
			(end 0.120396 0.3048)
			(stroke
				(width 0.1)
				(type default)
			)
			(layer "F.Fab")
		)
		(pad "1" smd circle
			(at -0.40005 0)
			(size 0 0)
			(layers "F.Cu" "F.Mask" "F.Paste")
			(net "P3V3_AUX")
		)
		(pad "2" smd circle
			(at 0.40005 0)
			(size 0 0)
			(layers "F.Cu" "F.Mask" "F.Paste")
			(net "SMB_IOEXP_3V3AUX_SDA")
		)
	)
)
